(kicad_pcb
	(version 20260206)
	(generator "pcbnew")
	(generator_version "10.0")
	(general
		(thickness 1.6)
		(legacy_teardrops no)
	)
	(paper "A4")
	(title_block
		(title "04192023_DAF0TMB3IC0_F0TG_MB_C_brd_V02_OCP.brd")
		(comment 1 "Grand Teton / footprints 4696-4702 of 8354")
	)
	(layers
		(0 "F.Cu" signal "TOP")
		(4 "In1.Cu" signal "GND")
		(6 "In2.Cu" signal "IN1")
		(8 "In3.Cu" signal "GND1")
		(10 "In4.Cu" signal "IN2")
		(12 "In5.Cu" signal "GND2")
		(14 "In6.Cu" signal "IN3")
		(16 "In7.Cu" signal "GND3")
		(18 "In8.Cu" signal "VCC")
		(20 "In9.Cu" signal "VCC1")
		(22 "In10.Cu" signal "GND4")
		(24 "In11.Cu" signal "IN4")
		(26 "In12.Cu" signal "GND5")
		(28 "In13.Cu" signal "IN5")
		(30 "In14.Cu" signal "GND6")
		(32 "In15.Cu" signal "IN6")
		(34 "In16.Cu" signal "GND7")
		(2 "B.Cu" signal "BOTTOM")
		(9 "F.Adhes" user "F.Adhesive")
		(11 "B.Adhes" user "B.Adhesive")
		(13 "F.Paste" user "Package Geometry/Pastemask Top")
		(15 "B.Paste" user "Package Geometry/Pastemask Bottom")
		(5 "F.SilkS" user "Ref Des/Silkscreen Top")
		(7 "B.SilkS" user "Ref Des/Silkscreen Bottom")
		(1 "F.Mask" user "Board Geometry/Soldermask Top")
		(3 "B.Mask" user "Board Geometry/Soldermask Bottom")
		(17 "Dwgs.User" user "User.Drawings")
		(19 "Cmts.User" user "User.Comments")
		(21 "Eco1.User" user "User.Eco1")
		(23 "Eco2.User" user "User.Eco2")
		(25 "Edge.Cuts" user "Board Geometry/Outline")
		(27 "Margin" user)
		(31 "F.CrtYd" user "Package Geometry/Place Bound Top")
		(29 "B.CrtYd" user "Package Geometry/Place Bound Bottom")
		(35 "F.Fab" user "Ref Des/Assembly Top")
		(33 "B.Fab" user "Ref Des/Assembly Bottom")
	)
	(footprint ""
		(layer "F.Cu")
		(at 156.30779 -101.638862 -90)
		(property "Reference" "R3297"
			(at 0 0 270)
			(layer "F.SilkS")
			(hide yes)
			(effects
				(font
					(size 1.27 1.27)
				)
			)
		)
		(property "Value" ""
			(at 0 0 270)
			(layer "F.Fab")
			(effects
				(font
					(size 1.27 1.27)
				)
			)
		)
		(duplicate_pad_numbers_are_jumpers no)
		(fp_line
			(start -0.7874 0.4064)
			(end -0.7874 -0.4064)
			(stroke
				(width 0.1524)
				(type default)
			)
			(layer "F.SilkS")
		)
		(fp_line
			(start 0.7874 0.4064)
			(end -0.7874 0.4064)
			(stroke
				(width 0.1524)
				(type default)
			)
			(layer "F.SilkS")
		)
		(fp_line
			(start -0.7874 -0.4064)
			(end 0.7874 -0.4064)
			(stroke
				(width 0.1524)
				(type default)
			)
			(layer "F.SilkS")
		)
		(fp_line
			(start 0.7874 -0.4064)
			(end 0.7874 0.4064)
			(stroke
				(width 0.1524)
				(type default)
			)
			(layer "F.SilkS")
		)
		(fp_line
			(start -0.67945 0.3048)
			(end -0.67945 -0.305054)
			(stroke
				(width 0.1)
				(type default)
			)
			(layer "F.Fab")
		)
		(fp_line
			(start -0.12065 0.3048)
			(end -0.67945 0.3048)
			(stroke
				(width 0.1)
				(type default)
			)
			(layer "F.Fab")
		)
		(fp_line
			(start 0.120396 0.3048)
			(end 0.120396 0.2794)
			(stroke
				(width 0.1)
				(type default)
			)
			(layer "F.Fab")
		)
		(fp_line
			(start 0.67945 0.3048)
			(end 0.120396 0.3048)
			(stroke
				(width 0.1)
				(type default)
			)
			(layer "F.Fab")
		)
		(fp_line
			(start -0.12065 0.2794)
			(end -0.12065 0.3048)
			(stroke
				(width 0.1)
				(type default)
			)
			(layer "F.Fab")
		)
		(fp_line
			(start 0.120396 0.2794)
			(end -0.12065 0.2794)
			(stroke
				(width 0.1)
				(type default)
			)
			(layer "F.Fab")
		)
		(fp_line
			(start -0.12065 -0.2794)
			(end 0.12065 -0.2794)
			(stroke
				(width 0.1)
				(type default)
			)
			(layer "F.Fab")
		)
		(fp_line
			(start 0.12065 -0.2794)
			(end 0.12065 -0.3048)
			(stroke
				(width 0.1)
				(type default)
			)
			(layer "F.Fab")
		)
		(fp_line
			(start 0.12065 -0.3048)
			(end 0.67945 -0.3048)
			(stroke
				(width 0.1)
				(type default)
			)
			(layer "F.Fab")
		)
		(fp_line
			(start 0.67945 -0.3048)
			(end 0.67945 0.3048)
			(stroke
				(width 0.1)
				(type default)
			)
			(layer "F.Fab")
		)
		(fp_line
			(start -0.67945 -0.305054)
			(end -0.12065 -0.305054)
			(stroke
				(width 0.1)
				(type default)
			)
			(layer "F.Fab")
		)
		(fp_line
			(start -0.12065 -0.305054)
			(end -0.12065 -0.2794)
			(stroke
				(width 0.1)
				(type default)
			)
			(layer "F.Fab")
		)
		(pad "1" smd circle
			(at -0.40005 0 270)
			(size 0 0)
			(layers "F.Cu" "F.Mask" "F.Paste")
			(net "LED_HDD_ACTIVITY_B_N")
		)
		(pad "2" smd circle
			(at 0.40005 0 270)
			(size 0 0)
			(layers "F.Cu" "F.Mask" "F.Paste")
			(net "GND")
		)
	)
	(footprint ""
		(layer "F.Cu")
		(at 348.9325 -15.924276 90)
		(property "Reference" "D46"
			(at -3.12674 0.141732 90)
			(unlocked yes)
			(layer "F.SilkS")
			(effects
				(font
					(size 0.7874 0.5842)
					(thickness 0.1524)
				)
				(justify left)
			)
		)
		(property "Value" ""
			(at 0 0 90)
			(layer "F.Fab")
			(effects
				(font
					(size 1.27 1.27)
				)
			)
		)
		(duplicate_pad_numbers_are_jumpers no)
		(fp_line
			(start 1.16078 -0.4826)
			(end 1.16078 0.4826)
			(stroke
				(width 0.1524)
				(type default)
			)
			(layer "F.SilkS")
		)
		(fp_line
			(start 1.03378 -0.4826)
			(end 1.03378 0.4826)
			(stroke
				(width 0.1524)
				(type default)
			)
			(layer "F.SilkS")
		)
		(fp_line
			(start 0.90678 -0.4826)
			(end 0.90678 0.4826)
			(stroke
				(width 0.1524)
				(type default)
			)
			(layer "F.SilkS")
		)
		(fp_line
			(start -0.64008 -0.4826)
			(end 1.16078 -0.4826)
			(stroke
				(width 0.1524)
				(type default)
			)
			(layer "F.SilkS")
		)
		(fp_line
			(start -0.79248 -0.4826)
			(end 1.03378 -0.4826)
			(stroke
				(width 0.1524)
				(type default)
			)
			(layer "F.SilkS")
		)
		(fp_line
			(start -0.89408 -0.4826)
			(end 0.90678 -0.4826)
			(stroke
				(width 0.1524)
				(type default)
			)
			(layer "F.SilkS")
		)
		(fp_line
			(start 1.16078 0.4826)
			(end -0.64008 0.4826)
			(stroke
				(width 0.1524)
				(type default)
			)
			(layer "F.SilkS")
		)
		(fp_line
			(start 1.03378 0.4826)
			(end -0.79248 0.4826)
			(stroke
				(width 0.1524)
				(type default)
			)
			(layer "F.SilkS")
		)
		(fp_line
			(start 0.90678 0.4826)
			(end -0.90678 0.4826)
			(stroke
				(width 0.1524)
				(type default)
			)
			(layer "F.SilkS")
		)
		(fp_line
			(start -0.90678 0.4826)
			(end -0.90678 -0.4699)
			(stroke
				(width 0.1524)
				(type default)
			)
			(layer "F.SilkS")
		)
		(fp_line
			(start 0.499872 -0.249936)
			(end 0.499872 0.249936)
			(stroke
				(width 0.1)
				(type default)
			)
			(layer "F.Fab")
		)
		(fp_line
			(start -0.499872 -0.249936)
			(end 0.499872 -0.249936)
			(stroke
				(width 0.1)
				(type default)
			)
			(layer "F.Fab")
		)
		(fp_line
			(start 0.499872 0.249936)
			(end -0.499872 0.249936)
			(stroke
				(width 0.1)
				(type default)
			)
			(layer "F.Fab")
		)
		(fp_line
			(start -0.499872 0.249936)
			(end -0.499872 -0.249936)
			(stroke
				(width 0.1)
				(type default)
			)
			(layer "F.Fab")
		)
		(pad "A" smd rect
			(at -0.47498 0 90)
			(size 0.6096 0.7112)
			(layers "F.Cu" "F.Mask" "F.Paste")
			(net "PU_P12V_ALL_PWROK_LED")
		)
		(pad "C" smd rect
			(at 0.47498 0 90)
			(size 0.6096 0.7112)
			(layers "F.Cu" "F.Mask" "F.Paste")
			(net "P12V_ALL_PWROK_N")
		)
	)
	(footprint ""
		(layer "F.Cu")
		(at 252.961648 -56.193182)
		(property "Reference" "PR3953"
			(at 0 0 0)
			(layer "F.SilkS")
			(hide yes)
			(effects
				(font
					(size 1.27 1.27)
				)
			)
		)
		(property "Value" ""
			(at 0 0 0)
			(layer "F.Fab")
			(effects
				(font
					(size 1.27 1.27)
				)
			)
		)
		(duplicate_pad_numbers_are_jumpers no)
		(fp_line
			(start -0.7874 -0.4064)
			(end 0.7874 -0.4064)
			(stroke
				(width 0.1524)
				(type default)
			)
			(layer "F.SilkS")
		)
		(fp_line
			(start -0.7874 0.4064)
			(end -0.7874 -0.4064)
			(stroke
				(width 0.1524)
				(type default)
			)
			(layer "F.SilkS")
		)
		(fp_line
			(start 0.7874 -0.4064)
			(end 0.7874 0.4064)
			(stroke
				(width 0.1524)
				(type default)
			)
			(layer "F.SilkS")
		)
		(fp_line
			(start 0.7874 0.4064)
			(end -0.7874 0.4064)
			(stroke
				(width 0.1524)
				(type default)
			)
			(layer "F.SilkS")
		)
		(fp_line
			(start -0.67945 -0.305054)
			(end -0.12065 -0.305054)
			(stroke
				(width 0.1)
				(type default)
			)
			(layer "F.Fab")
		)
		(fp_line
			(start -0.67945 0.3048)
			(end -0.67945 -0.305054)
			(stroke
				(width 0.1)
				(type default)
			)
			(layer "F.Fab")
		)
		(fp_line
			(start -0.12065 -0.305054)
			(end -0.12065 -0.2794)
			(stroke
				(width 0.1)
				(type default)
			)
			(layer "F.Fab")
		)
		(fp_line
			(start -0.12065 -0.2794)
			(end 0.12065 -0.2794)
			(stroke
				(width 0.1)
				(type default)
			)
			(layer "F.Fab")
		)
		(fp_line
			(start -0.12065 0.2794)
			(end -0.12065 0.3048)
			(stroke
				(width 0.1)
				(type default)
			)
			(layer "F.Fab")
		)
		(fp_line
			(start -0.12065 0.3048)
			(end -0.67945 0.3048)
			(stroke
				(width 0.1)
				(type default)
			)
			(layer "F.Fab")
		)
		(fp_line
			(start 0.120396 0.2794)
			(end -0.12065 0.2794)
			(stroke
				(width 0.1)
				(type default)
			)
			(layer "F.Fab")
		)
		(fp_line
			(start 0.120396 0.3048)
			(end 0.120396 0.2794)
			(stroke
				(width 0.1)
				(type default)
			)
			(layer "F.Fab")
		)
		(fp_line
			(start 0.12065 -0.3048)
			(end 0.67945 -0.3048)
			(stroke
				(width 0.1)
				(type default)
			)
			(layer "F.Fab")
		)
		(fp_line
			(start 0.12065 -0.2794)
			(end 0.12065 -0.3048)
			(stroke
				(width 0.1)
				(type default)
			)
			(layer "F.Fab")
		)
		(fp_line
			(start 0.67945 -0.3048)
			(end 0.67945 0.3048)
			(stroke
				(width 0.1)
				(type default)
			)
			(layer "F.Fab")
		)
		(fp_line
			(start 0.67945 0.3048)
			(end 0.120396 0.3048)
			(stroke
				(width 0.1)
				(type default)
			)
			(layer "F.Fab")
		)
		(pad "1" smd circle
			(at -0.40005 0)
			(size 0 0)
			(layers "F.Cu" "F.Mask" "F.Paste")
			(net "P12V_AUX")
		)
		(pad "2" smd circle
			(at 0.40005 0)
			(size 0 0)
			(layers "F.Cu" "F.Mask" "F.Paste")
			(net "P12V_E1S_OV_FB_0")
		)
	)
	(footprint ""
		(layer "F.Cu")
		(at 448.717924 -397.399002 -90)
		(property "Reference" "PC6554_1"
			(at 0 0 270)
			(layer "F.SilkS")
			(hide yes)
			(effects
				(font
					(size 1.27 1.27)
				)
			)
		)
		(property "Value" ""
			(at 0 0 270)
			(layer "F.Fab")
			(effects
				(font
					(size 1.27 1.27)
				)
			)
		)
		(duplicate_pad_numbers_are_jumpers no)
		(fp_line
			(start -0.7874 0.4064)
			(end -0.7874 -0.4064)
			(stroke
				(width 0.1524)
				(type default)
			)
			(layer "F.SilkS")
		)
		(fp_line
			(start 0.7874 0.4064)
			(end -0.7874 0.4064)
			(stroke
				(width 0.1524)
				(type default)
			)
			(layer "F.SilkS")
		)
		(fp_line
			(start -0.7874 -0.4064)
			(end 0.7874 -0.4064)
			(stroke
				(width 0.1524)
				(type default)
			)
			(layer "F.SilkS")
		)
		(fp_line
			(start 0.7874 -0.4064)
			(end 0.7874 0.4064)
			(stroke
				(width 0.1524)
				(type default)
			)
			(layer "F.SilkS")
		)
		(fp_line
			(start -0.67945 0.3048)
			(end -0.67945 -0.305054)
			(stroke
				(width 0.1)
				(type default)
			)
			(layer "F.Fab")
		)
		(fp_line
			(start -0.12065 0.3048)
			(end -0.67945 0.3048)
			(stroke
				(width 0.1)
				(type default)
			)
			(layer "F.Fab")
		)
		(fp_line
			(start 0.120396 0.3048)
			(end 0.120396 0.2794)
			(stroke
				(width 0.1)
				(type default)
			)
			(layer "F.Fab")
		)
		(fp_line
			(start 0.67945 0.3048)
			(end 0.120396 0.3048)
			(stroke
				(width 0.1)
				(type default)
			)
			(layer "F.Fab")
		)
		(fp_line
			(start -0.12065 0.2794)
			(end -0.12065 0.3048)
			(stroke
				(width 0.1)
				(type default)
			)
			(layer "F.Fab")
		)
		(fp_line
			(start 0.120396 0.2794)
			(end -0.12065 0.2794)
			(stroke
				(width 0.1)
				(type default)
			)
			(layer "F.Fab")
		)
		(fp_line
			(start -0.12065 -0.2794)
			(end 0.12065 -0.2794)
			(stroke
				(width 0.1)
				(type default)
			)
			(layer "F.Fab")
		)
		(fp_line
			(start 0.12065 -0.2794)
			(end 0.12065 -0.3048)
			(stroke
				(width 0.1)
				(type default)
			)
			(layer "F.Fab")
		)
		(fp_line
			(start 0.12065 -0.3048)
			(end 0.67945 -0.3048)
			(stroke
				(width 0.1)
				(type default)
			)
			(layer "F.Fab")
		)
		(fp_line
			(start 0.67945 -0.3048)
			(end 0.67945 0.3048)
			(stroke
				(width 0.1)
				(type default)
			)
			(layer "F.Fab")
		)
		(fp_line
			(start -0.67945 -0.305054)
			(end -0.12065 -0.305054)
			(stroke
				(width 0.1)
				(type default)
			)
			(layer "F.Fab")
		)
		(fp_line
			(start -0.12065 -0.305054)
			(end -0.12065 -0.2794)
			(stroke
				(width 0.1)
				(type default)
			)
			(layer "F.Fab")
		)
		(pad "1" smd circle
			(at -0.40005 0 270)
			(size 0 0)
			(layers "F.Cu" "F.Mask" "F.Paste")
			(net "SW_P12V_AUX_P0V9_RETIMER_CPU0_FLT")
		)
		(pad "2" smd circle
			(at 0.40005 0 270)
			(size 0 0)
			(layers "F.Cu" "F.Mask" "F.Paste")
			(net "GND")
		)
	)
	(footprint ""
		(layer "F.Cu")
		(at 166.3192 -433.878736 180)
		(property "Reference" "R3106"
			(at 0 0 180)
			(layer "F.SilkS")
			(hide yes)
			(effects
				(font
					(size 1.27 1.27)
				)
			)
		)
		(property "Value" ""
			(at 0 0 180)
			(layer "F.Fab")
			(effects
				(font
					(size 1.27 1.27)
				)
			)
		)
		(duplicate_pad_numbers_are_jumpers no)
		(fp_line
			(start 0.7874 0.4064)
			(end -0.7874 0.4064)
			(stroke
				(width 0.1524)
				(type default)
			)
			(layer "F.SilkS")
		)
		(fp_line
			(start 0.7874 -0.4064)
			(end 0.7874 0.4064)
			(stroke
				(width 0.1524)
				(type default)
			)
			(layer "F.SilkS")
		)
		(fp_line
			(start -0.7874 0.4064)
			(end -0.7874 -0.4064)
			(stroke
				(width 0.1524)
				(type default)
			)
			(layer "F.SilkS")
		)
		(fp_line
			(start -0.7874 -0.4064)
			(end 0.7874 -0.4064)
			(stroke
				(width 0.1524)
				(type default)
			)
			(layer "F.SilkS")
		)
		(fp_line
			(start 0.67945 0.3048)
			(end 0.120396 0.3048)
			(stroke
				(width 0.1)
				(type default)
			)
			(layer "F.Fab")
		)
		(fp_line
			(start 0.67945 -0.3048)
			(end 0.67945 0.3048)
			(stroke
				(width 0.1)
				(type default)
			)
			(layer "F.Fab")
		)
		(fp_line
			(start 0.12065 -0.2794)
			(end 0.12065 -0.3048)
			(stroke
				(width 0.1)
				(type default)
			)
			(layer "F.Fab")
		)
		(fp_line
			(start 0.12065 -0.3048)
			(end 0.67945 -0.3048)
			(stroke
				(width 0.1)
				(type default)
			)
			(layer "F.Fab")
		)
		(fp_line
			(start 0.120396 0.3048)
			(end 0.120396 0.2794)
			(stroke
				(width 0.1)
				(type default)
			)
			(layer "F.Fab")
		)
		(fp_line
			(start 0.120396 0.2794)
			(end -0.12065 0.2794)
			(stroke
				(width 0.1)
				(type default)
			)
			(layer "F.Fab")
		)
		(fp_line
			(start -0.12065 0.3048)
			(end -0.67945 0.3048)
			(stroke
				(width 0.1)
				(type default)
			)
			(layer "F.Fab")
		)
		(fp_line
			(start -0.12065 0.2794)
			(end -0.12065 0.3048)
			(stroke
				(width 0.1)
				(type default)
			)
			(layer "F.Fab")
		)
		(fp_line
			(start -0.12065 -0.2794)
			(end 0.12065 -0.2794)
			(stroke
				(width 0.1)
				(type default)
			)
			(layer "F.Fab")
		)
		(fp_line
			(start -0.12065 -0.305054)
			(end -0.12065 -0.2794)
			(stroke
				(width 0.1)
				(type default)
			)
			(layer "F.Fab")
		)
		(fp_line
			(start -0.67945 0.3048)
			(end -0.67945 -0.305054)
			(stroke
				(width 0.1)
				(type default)
			)
			(layer "F.Fab")
		)
		(fp_line
			(start -0.67945 -0.305054)
			(end -0.12065 -0.305054)
			(stroke
				(width 0.1)
				(type default)
			)
			(layer "F.Fab")
		)
		(pad "1" smd circle
			(at -0.40005 0 180)
			(size 0 0)
			(layers "F.Cu" "F.Mask" "F.Paste")
			(net "SMB_BMC_SWB_SDA")
		)
		(pad "2" smd circle
			(at 0.40005 0 180)
			(size 0 0)
			(layers "F.Cu" "F.Mask" "F.Paste")
			(net "SMB_BMC_SWB_R_SDA")
		)
	)
	(footprint ""
		(layer "F.Cu")
		(at 332.071472 -396.412974 90)
		(property "Reference" "R630"
			(at 0 0 90)
			(layer "F.SilkS")
			(hide yes)
			(effects
				(font
					(size 1.27 1.27)
				)
			)
		)
		(property "Value" ""
			(at 0 0 90)
			(layer "F.Fab")
			(effects
				(font
					(size 1.27 1.27)
				)
			)
		)
		(duplicate_pad_numbers_are_jumpers no)
		(fp_line
			(start 0.32512 -0.175006)
			(end 0.32512 0.175006)
			(stroke
				(width 0.1)
				(type default)
			)
			(layer "F.Fab")
		)
		(fp_line
			(start -0.32512 -0.175006)
			(end 0.32512 -0.175006)
			(stroke
				(width 0.1)
				(type default)
			)
			(layer "F.Fab")
		)
		(fp_line
			(start 0.32512 0.175006)
			(end -0.32512 0.175006)
			(stroke
				(width 0.1)
				(type default)
			)
			(layer "F.Fab")
		)
		(fp_line
			(start -0.32512 0.175006)
			(end -0.32512 -0.175006)
			(stroke
				(width 0.1)
				(type default)
			)
			(layer "F.Fab")
		)
		(pad "1" smd rect
			(at -0.2667 0 90)
			(size 0.3048 0.381)
			(layers "F.Cu" "F.Mask" "F.Paste")
			(net "CLK_100M_RETIMER_CPU0_P1_DP")
		)
		(pad "2" smd rect
			(at 0.2667 0 270)
			(size 0.3048 0.381)
			(layers "F.Cu" "F.Mask" "F.Paste")
			(net "GND")
		)
	)
	(footprint ""
		(layer "F.Cu")
		(at 437.240172 -32.173418 90)
		(property "Reference" "R3871"
			(at 0 0 90)
			(layer "F.SilkS")
			(hide yes)
			(effects
				(font
					(size 1.27 1.27)
				)
			)
		)
		(property "Value" ""
			(at 0 0 90)
			(layer "F.Fab")
			(effects
				(font
					(size 1.27 1.27)
				)
			)
		)
		(duplicate_pad_numbers_are_jumpers no)
		(fp_line
			(start 0.7874 -0.4064)
			(end 0.7874 0.4064)
			(stroke
				(width 0.1524)
				(type default)
			)
			(layer "F.SilkS")
		)
		(fp_line
			(start -0.7874 -0.4064)
			(end 0.7874 -0.4064)
			(stroke
				(width 0.1524)
				(type default)
			)
			(layer "F.SilkS")
		)
		(fp_line
			(start 0.7874 0.4064)
			(end -0.7874 0.4064)
			(stroke
				(width 0.1524)
				(type default)
			)
			(layer "F.SilkS")
		)
		(fp_line
			(start -0.7874 0.4064)
			(end -0.7874 -0.4064)
			(stroke
				(width 0.1524)
				(type default)
			)
			(layer "F.SilkS")
		)
		(fp_line
			(start -0.12065 -0.305054)
			(end -0.12065 -0.2794)
			(stroke
				(width 0.1)
				(type default)
			)
			(layer "F.Fab")
		)
		(fp_line
			(start -0.67945 -0.305054)
			(end -0.12065 -0.305054)
			(stroke
				(width 0.1)
				(type default)
			)
			(layer "F.Fab")
		)
		(fp_line
			(start 0.67945 -0.3048)
			(end 0.67945 0.3048)
			(stroke
				(width 0.1)
				(type default)
			)
			(layer "F.Fab")
		)
		(fp_line
			(start 0.12065 -0.3048)
			(end 0.67945 -0.3048)
			(stroke
				(width 0.1)
				(type default)
			)
			(layer "F.Fab")
		)
		(fp_line
			(start 0.12065 -0.2794)
			(end 0.12065 -0.3048)
			(stroke
				(width 0.1)
				(type default)
			)
			(layer "F.Fab")
		)
		(fp_line
			(start -0.12065 -0.2794)
			(end 0.12065 -0.2794)
			(stroke
				(width 0.1)
				(type default)
			)
			(layer "F.Fab")
		)
		(fp_line
			(start 0.120396 0.2794)
			(end -0.12065 0.2794)
			(stroke
				(width 0.1)
				(type default)
			)
			(layer "F.Fab")
		)
		(fp_line
			(start -0.12065 0.2794)
			(end -0.12065 0.3048)
			(stroke
				(width 0.1)
				(type default)
			)
			(layer "F.Fab")
		)
		(fp_line
			(start 0.67945 0.3048)
			(end 0.120396 0.3048)
			(stroke
				(width 0.1)
				(type default)
			)
			(layer "F.Fab")
		)
		(fp_line
			(start 0.120396 0.3048)
			(end 0.120396 0.2794)
			(stroke
				(width 0.1)
				(type default)
			)
			(layer "F.Fab")
		)
		(fp_line
			(start -0.12065 0.3048)
			(end -0.67945 0.3048)
			(stroke
				(width 0.1)
				(type default)
			)
			(layer "F.Fab")
		)
		(fp_line
			(start -0.67945 0.3048)
			(end -0.67945 -0.305054)
			(stroke
				(width 0.1)
				(type default)
			)
			(layer "F.Fab")
		)
		(pad "1" smd circle
			(at -0.40005 0 90)
			(size 0 0)
			(layers "F.Cu" "F.Mask" "F.Paste")
			(net "P12V_OCP_IMON_1")
		)
		(pad "2" smd circle
			(at 0.40005 0 90)
			(size 0 0)
			(layers "F.Cu" "F.Mask" "F.Paste")
			(net "P12V_OCP_SFF_ISENSE_MPS_MAM")
		)
	)
)
